(kicad_pcb
	(version 20260206)
	(generator "pcbnew")
	(generator_version "10.0")
	(general
		(thickness 1.6)
		(legacy_teardrops no)
	)
	(paper "A4")
	(title_block
		(title "03242023_DA0F0TMBIJ0_F0T_Motherboard_J_brd_V01_OCP.brd")
		(comment 1 "Grand Teton / footprints 5897-5903 of 6105")
	)
	(layers
		(0 "F.Cu" signal "TOP")
		(4 "In1.Cu" signal "GND")
		(6 "In2.Cu" signal "IN1")
		(8 "In3.Cu" signal "GND1")
		(10 "In4.Cu" signal "IN2")
		(12 "In5.Cu" signal "GND2")
		(14 "In6.Cu" signal "IN3")
		(16 "In7.Cu" signal "GND3")
		(18 "In8.Cu" signal "VCC")
		(20 "In9.Cu" signal "VCC1")
		(22 "In10.Cu" signal "GND4")
		(24 "In11.Cu" signal "IN4")
		(26 "In12.Cu" signal "GND5")
		(28 "In13.Cu" signal "IN5")
		(30 "In14.Cu" signal "GND6")
		(32 "In15.Cu" signal "IN6")
		(34 "In16.Cu" signal "GND7")
		(2 "B.Cu" signal "BOTTOM")
		(9 "F.Adhes" user "F.Adhesive")
		(11 "B.Adhes" user "B.Adhesive")
		(13 "F.Paste" user "Package Geometry/Pastemask Top")
		(15 "B.Paste" user "Package Geometry/Pastemask Bottom")
		(5 "F.SilkS" user "Ref Des/Silkscreen Top")
		(7 "B.SilkS" user "Ref Des/Silkscreen Bottom")
		(1 "F.Mask" user "Board Geometry/Soldermask Top")
		(3 "B.Mask" user "Board Geometry/Soldermask Bottom")
		(17 "Dwgs.User" user "User.Drawings")
		(19 "Cmts.User" user "User.Comments")
		(21 "Eco1.User" user "User.Eco1")
		(23 "Eco2.User" user "User.Eco2")
		(25 "Edge.Cuts" user "Board Geometry/Outline")
		(27 "Margin" user)
		(31 "F.CrtYd" user "Package Geometry/Place Bound Top")
		(29 "B.CrtYd" user "Package Geometry/Place Bound Bottom")
		(35 "F.Fab" user "Ref Des/Assembly Top")
		(33 "B.Fab" user "Ref Des/Assembly Bottom")
	)
	(footprint ""
		(layer "B.Cu")
		(at 176.955704 -113.77549)
		(property "Reference" "C1150"
			(at 0 0 0)
			(layer "B.SilkS")
			(hide yes)
			(effects
				(font
					(size 1.27 1.27)
				)
				(justify mirror)
			)
		)
		(property "Value" ""
			(at 0 0 0)
			(layer "B.Fab")
			(effects
				(font
					(size 1.27 1.27)
				)
				(justify mirror)
			)
		)
		(duplicate_pad_numbers_are_jumpers no)
		(fp_line
			(start -0.69215 -0.2921)
			(end -0.69215 0.2921)
			(stroke
				(width 0.1524)
				(type default)
			)
			(layer "B.SilkS")
		)
		(fp_line
			(start -0.69215 0.2921)
			(end 0.69215 0.2921)
			(stroke
				(width 0.1524)
				(type default)
			)
			(layer "B.SilkS")
		)
		(fp_line
			(start 0.69215 -0.2921)
			(end -0.69215 -0.2921)
			(stroke
				(width 0.1524)
				(type default)
			)
			(layer "B.SilkS")
		)
		(fp_line
			(start 0.69215 0.2921)
			(end 0.69215 -0.2921)
			(stroke
				(width 0.1524)
				(type default)
			)
			(layer "B.SilkS")
		)
		(fp_line
			(start -0.51435 -0.2794)
			(end -0.51435 0.2794)
			(stroke
				(width 0.1)
				(type default)
			)
			(layer "B.Fab")
		)
		(fp_line
			(start -0.51435 0.2794)
			(end 0.51435 0.2794)
			(stroke
				(width 0.1)
				(type default)
			)
			(layer "B.Fab")
		)
		(fp_line
			(start 0.51435 -0.2794)
			(end -0.51435 -0.2794)
			(stroke
				(width 0.1)
				(type default)
			)
			(layer "B.Fab")
		)
		(fp_line
			(start 0.51435 0.2794)
			(end 0.51435 -0.2794)
			(stroke
				(width 0.1)
				(type default)
			)
			(layer "B.Fab")
		)
		(pad "1" smd circle
			(at 0.40005 0 180)
			(size 0 0)
			(layers "B.Cu" "B.Mask" "B.Paste")
			(net "VCC_PLD_CORE")
		)
		(pad "2" smd circle
			(at -0.40005 0 180)
			(size 0 0)
			(layers "B.Cu" "B.Mask" "B.Paste")
			(net "GND")
		)
		(zone
			(layer "B.Cu")
			(hatch none 0.5)
			(connect_pads
				(clearance 0)
			)
			(min_thickness 0.25)
			(keepout
				(tracks not_allowed)
				(vias allowed)
				(pads allowed)
				(copperpour not_allowed)
				(footprints allowed)
			)
			(placement
				(enabled no)
				(sheetname "")
			)
			(fill
				(thermal_gap 0.5)
				(thermal_bridge_width 0.5)
				(island_removal_mode 0)
			)
			(polygon
				(pts
					(xy 177.146204 -113.68786) (xy 177.054764 -113.629694) (xy 176.855374 -113.629694) (xy 176.765204 -113.68786)
					(xy 176.765204 -113.86312) (xy 176.855374 -113.92154) (xy 177.054764 -113.92154) (xy 177.146204 -113.863374)
				)
			)
		)
	)
	(footprint ""
		(layer "B.Cu")
		(at 151.059388 -188.20257)
		(property "Reference" "R288"
			(at 0 0 0)
			(layer "B.SilkS")
			(hide yes)
			(effects
				(font
					(size 1.27 1.27)
				)
				(justify mirror)
			)
		)
		(property "Value" ""
			(at 0 0 0)
			(layer "B.Fab")
			(effects
				(font
					(size 1.27 1.27)
				)
				(justify mirror)
			)
		)
		(duplicate_pad_numbers_are_jumpers no)
		(fp_line
			(start -0.7874 -0.4064)
			(end -0.7874 0.4064)
			(stroke
				(width 0.1524)
				(type default)
			)
			(layer "B.SilkS")
		)
		(fp_line
			(start -0.7874 0.4064)
			(end 0.7874 0.4064)
			(stroke
				(width 0.1524)
				(type default)
			)
			(layer "B.SilkS")
		)
		(fp_line
			(start 0.7874 -0.4064)
			(end -0.7874 -0.4064)
			(stroke
				(width 0.1524)
				(type default)
			)
			(layer "B.SilkS")
		)
		(fp_line
			(start 0.7874 0.4064)
			(end 0.7874 -0.4064)
			(stroke
				(width 0.1524)
				(type default)
			)
			(layer "B.SilkS")
		)
		(fp_line
			(start -0.67945 -0.3048)
			(end -0.67945 0.3048)
			(stroke
				(width 0.1)
				(type default)
			)
			(layer "B.Fab")
		)
		(fp_line
			(start -0.67945 0.3048)
			(end -0.120396 0.3048)
			(stroke
				(width 0.1)
				(type default)
			)
			(layer "B.Fab")
		)
		(fp_line
			(start -0.12065 -0.3048)
			(end -0.67945 -0.3048)
			(stroke
				(width 0.1)
				(type default)
			)
			(layer "B.Fab")
		)
		(fp_line
			(start -0.12065 -0.2794)
			(end -0.12065 -0.3048)
			(stroke
				(width 0.1)
				(type default)
			)
			(layer "B.Fab")
		)
		(fp_line
			(start -0.120396 0.2794)
			(end 0.12065 0.2794)
			(stroke
				(width 0.1)
				(type default)
			)
			(layer "B.Fab")
		)
		(fp_line
			(start -0.120396 0.3048)
			(end -0.120396 0.2794)
			(stroke
				(width 0.1)
				(type default)
			)
			(layer "B.Fab")
		)
		(fp_line
			(start 0.12065 -0.305054)
			(end 0.12065 -0.2794)
			(stroke
				(width 0.1)
				(type default)
			)
			(layer "B.Fab")
		)
		(fp_line
			(start 0.12065 -0.2794)
			(end -0.12065 -0.2794)
			(stroke
				(width 0.1)
				(type default)
			)
			(layer "B.Fab")
		)
		(fp_line
			(start 0.12065 0.2794)
			(end 0.12065 0.3048)
			(stroke
				(width 0.1)
				(type default)
			)
			(layer "B.Fab")
		)
		(fp_line
			(start 0.12065 0.3048)
			(end 0.67945 0.3048)
			(stroke
				(width 0.1)
				(type default)
			)
			(layer "B.Fab")
		)
		(fp_line
			(start 0.67945 -0.305054)
			(end 0.12065 -0.305054)
			(stroke
				(width 0.1)
				(type default)
			)
			(layer "B.Fab")
		)
		(fp_line
			(start 0.67945 0.3048)
			(end 0.67945 -0.305054)
			(stroke
				(width 0.1)
				(type default)
			)
			(layer "B.Fab")
		)
		(pad "1" smd circle
			(at 0.40005 0 180)
			(size 0 0)
			(layers "B.Cu" "B.Mask" "B.Paste")
			(net "PVNN_TERM_CPU0")
		)
		(pad "2" smd circle
			(at -0.40005 0 180)
			(size 0 0)
			(layers "B.Cu" "B.Mask" "B.Paste")
			(net "PD_CPU1_TXT_PLTEN")
		)
	)
	(footprint ""
		(layer "B.Cu")
		(at 102.495604 -294.01008 180)
		(property "Reference" "C322"
			(at 0 0 0)
			(layer "B.SilkS")
			(hide yes)
			(effects
				(font
					(size 1.27 1.27)
				)
				(justify mirror)
			)
		)
		(property "Value" ""
			(at 0 0 0)
			(layer "B.Fab")
			(effects
				(font
					(size 1.27 1.27)
				)
				(justify mirror)
			)
		)
		(duplicate_pad_numbers_are_jumpers no)
		(fp_line
			(start 1.524 0.762)
			(end 1.524 -0.762)
			(stroke
				(width 0.1524)
				(type default)
			)
			(layer "B.SilkS")
		)
		(fp_line
			(start 1.524 -0.762)
			(end -1.524 -0.762)
			(stroke
				(width 0.1524)
				(type default)
			)
			(layer "B.SilkS")
		)
		(fp_line
			(start -1.524 0.762)
			(end 1.524 0.762)
			(stroke
				(width 0.1524)
				(type default)
			)
			(layer "B.SilkS")
		)
		(fp_line
			(start -1.524 -0.762)
			(end -1.524 0.762)
			(stroke
				(width 0.1524)
				(type default)
			)
			(layer "B.SilkS")
		)
		(fp_line
			(start 1.1049 0.724916)
			(end -1.1049 0.724916)
			(stroke
				(width 0.1)
				(type default)
			)
			(layer "B.Fab")
		)
		(fp_line
			(start 1.1049 -0.724916)
			(end 1.1049 0.724916)
			(stroke
				(width 0.1)
				(type default)
			)
			(layer "B.Fab")
		)
		(fp_line
			(start -1.1049 0.724916)
			(end -1.1049 -0.724916)
			(stroke
				(width 0.1)
				(type default)
			)
			(layer "B.Fab")
		)
		(fp_line
			(start -1.1049 -0.724916)
			(end 1.1049 -0.724916)
			(stroke
				(width 0.1)
				(type default)
			)
			(layer "B.Fab")
		)
		(pad "1" smd rect
			(at 0.889 0 180)
			(size 1.016 1.27)
			(layers "B.Cu" "B.Mask" "B.Paste")
			(net "PVCCIN_CPU1")
		)
		(pad "2" smd rect
			(at -0.889 0 180)
			(size 1.016 1.27)
			(layers "B.Cu" "B.Mask" "B.Paste")
			(net "GND")
		)
	)
	(footprint ""
		(layer "B.Cu")
		(at 420.152322 -318.05499 90)
		(property "Reference" "R3886"
			(at 0 0 90)
			(layer "B.SilkS")
			(hide yes)
			(effects
				(font
					(size 1.27 1.27)
				)
				(justify mirror)
			)
		)
		(property "Value" ""
			(at 0 0 90)
			(layer "B.Fab")
			(effects
				(font
					(size 1.27 1.27)
				)
				(justify mirror)
			)
		)
		(duplicate_pad_numbers_are_jumpers no)
		(fp_line
			(start 0.7874 -0.4064)
			(end -0.7874 -0.4064)
			(stroke
				(width 0.1524)
				(type default)
			)
			(layer "B.SilkS")
		)
		(fp_line
			(start -0.7874 -0.4064)
			(end -0.7874 0.4064)
			(stroke
				(width 0.1524)
				(type default)
			)
			(layer "B.SilkS")
		)
		(fp_line
			(start 0.7874 0.4064)
			(end 0.7874 -0.4064)
			(stroke
				(width 0.1524)
				(type default)
			)
			(layer "B.SilkS")
		)
		(fp_line
			(start -0.7874 0.4064)
			(end 0.7874 0.4064)
			(stroke
				(width 0.1524)
				(type default)
			)
			(layer "B.SilkS")
		)
		(fp_line
			(start 0.67945 -0.305054)
			(end 0.12065 -0.305054)
			(stroke
				(width 0.1)
				(type default)
			)
			(layer "B.Fab")
		)
		(fp_line
			(start 0.12065 -0.305054)
			(end 0.12065 -0.2794)
			(stroke
				(width 0.1)
				(type default)
			)
			(layer "B.Fab")
		)
		(fp_line
			(start -0.12065 -0.3048)
			(end -0.67945 -0.3048)
			(stroke
				(width 0.1)
				(type default)
			)
			(layer "B.Fab")
		)
		(fp_line
			(start -0.67945 -0.3048)
			(end -0.67945 0.3048)
			(stroke
				(width 0.1)
				(type default)
			)
			(layer "B.Fab")
		)
		(fp_line
			(start 0.12065 -0.2794)
			(end -0.12065 -0.2794)
			(stroke
				(width 0.1)
				(type default)
			)
			(layer "B.Fab")
		)
		(fp_line
			(start -0.12065 -0.2794)
			(end -0.12065 -0.3048)
			(stroke
				(width 0.1)
				(type default)
			)
			(layer "B.Fab")
		)
		(fp_line
			(start 0.12065 0.2794)
			(end 0.12065 0.3048)
			(stroke
				(width 0.1)
				(type default)
			)
			(layer "B.Fab")
		)
		(fp_line
			(start -0.120396 0.2794)
			(end 0.12065 0.2794)
			(stroke
				(width 0.1)
				(type default)
			)
			(layer "B.Fab")
		)
		(fp_line
			(start 0.67945 0.3048)
			(end 0.67945 -0.305054)
			(stroke
				(width 0.1)
				(type default)
			)
			(layer "B.Fab")
		)
		(fp_line
			(start 0.12065 0.3048)
			(end 0.67945 0.3048)
			(stroke
				(width 0.1)
				(type default)
			)
			(layer "B.Fab")
		)
		(fp_line
			(start -0.120396 0.3048)
			(end -0.120396 0.2794)
			(stroke
				(width 0.1)
				(type default)
			)
			(layer "B.Fab")
		)
		(fp_line
			(start -0.67945 0.3048)
			(end -0.120396 0.3048)
			(stroke
				(width 0.1)
				(type default)
			)
			(layer "B.Fab")
		)
		(pad "1" smd circle
			(at 0.40005 0 270)
			(size 0 0)
			(layers "B.Cu" "B.Mask" "B.Paste")
			(net "I3C_SPD_DDREFGH_CPU0_LVC1_SCL_3")
		)
		(pad "2" smd circle
			(at -0.40005 0 270)
			(size 0 0)
			(layers "B.Cu" "B.Mask" "B.Paste")
			(net "I3C_SPD_DDREFGH_CPU0_LVC1_SCL")
		)
	)
	(footprint ""
		(layer "B.Cu")
		(at 211.69503 -57.078372 -90)
		(property "Reference" "R3752"
			(at 0 0 90)
			(layer "B.SilkS")
			(hide yes)
			(effects
				(font
					(size 1.27 1.27)
				)
				(justify mirror)
			)
		)
		(property "Value" ""
			(at 0 0 90)
			(layer "B.Fab")
			(effects
				(font
					(size 1.27 1.27)
				)
				(justify mirror)
			)
		)
		(duplicate_pad_numbers_are_jumpers no)
		(fp_line
			(start -0.7874 0.4064)
			(end 0.7874 0.4064)
			(stroke
				(width 0.1524)
				(type default)
			)
			(layer "B.SilkS")
		)
		(fp_line
			(start 0.7874 0.4064)
			(end 0.7874 -0.4064)
			(stroke
				(width 0.1524)
				(type default)
			)
			(layer "B.SilkS")
		)
		(fp_line
			(start -0.7874 -0.4064)
			(end -0.7874 0.4064)
			(stroke
				(width 0.1524)
				(type default)
			)
			(layer "B.SilkS")
		)
		(fp_line
			(start 0.7874 -0.4064)
			(end -0.7874 -0.4064)
			(stroke
				(width 0.1524)
				(type default)
			)
			(layer "B.SilkS")
		)
		(fp_line
			(start -0.67945 0.3048)
			(end -0.120396 0.3048)
			(stroke
				(width 0.1)
				(type default)
			)
			(layer "B.Fab")
		)
		(fp_line
			(start -0.120396 0.3048)
			(end -0.120396 0.2794)
			(stroke
				(width 0.1)
				(type default)
			)
			(layer "B.Fab")
		)
		(fp_line
			(start 0.12065 0.3048)
			(end 0.67945 0.3048)
			(stroke
				(width 0.1)
				(type default)
			)
			(layer "B.Fab")
		)
		(fp_line
			(start 0.67945 0.3048)
			(end 0.67945 -0.305054)
			(stroke
				(width 0.1)
				(type default)
			)
			(layer "B.Fab")
		)
		(fp_line
			(start -0.120396 0.2794)
			(end 0.12065 0.2794)
			(stroke
				(width 0.1)
				(type default)
			)
			(layer "B.Fab")
		)
		(fp_line
			(start 0.12065 0.2794)
			(end 0.12065 0.3048)
			(stroke
				(width 0.1)
				(type default)
			)
			(layer "B.Fab")
		)
		(fp_line
			(start -0.12065 -0.2794)
			(end -0.12065 -0.3048)
			(stroke
				(width 0.1)
				(type default)
			)
			(layer "B.Fab")
		)
		(fp_line
			(start 0.12065 -0.2794)
			(end -0.12065 -0.2794)
			(stroke
				(width 0.1)
				(type default)
			)
			(layer "B.Fab")
		)
		(fp_line
			(start -0.67945 -0.3048)
			(end -0.67945 0.3048)
			(stroke
				(width 0.1)
				(type default)
			)
			(layer "B.Fab")
		)
		(fp_line
			(start -0.12065 -0.3048)
			(end -0.67945 -0.3048)
			(stroke
				(width 0.1)
				(type default)
			)
			(layer "B.Fab")
		)
		(fp_line
			(start 0.12065 -0.305054)
			(end 0.12065 -0.2794)
			(stroke
				(width 0.1)
				(type default)
			)
			(layer "B.Fab")
		)
		(fp_line
			(start 0.67945 -0.305054)
			(end 0.12065 -0.305054)
			(stroke
				(width 0.1)
				(type default)
			)
			(layer "B.Fab")
		)
		(pad "1" smd circle
			(at 0.40005 0 90)
			(size 0 0)
			(layers "B.Cu" "B.Mask" "B.Paste")
			(net "E1S_0_P3V3_ADC_ALERT_R")
		)
		(pad "2" smd circle
			(at -0.40005 0 90)
			(size 0 0)
			(layers "B.Cu" "B.Mask" "B.Paste")
			(net "E1S_0_P3V3_ADC_ALERT")
		)
	)
	(footprint ""
		(layer "B.Cu")
		(at 331.09408 -25.212548)
		(property "Reference" "R4097"
			(at 0 0 0)
			(layer "B.SilkS")
			(hide yes)
			(effects
				(font
					(size 1.27 1.27)
				)
				(justify mirror)
			)
		)
		(property "Value" ""
			(at 0 0 0)
			(layer "B.Fab")
			(effects
				(font
					(size 1.27 1.27)
				)
				(justify mirror)
			)
		)
		(duplicate_pad_numbers_are_jumpers no)
		(fp_line
			(start -0.7874 -0.4064)
			(end -0.7874 0.4064)
			(stroke
				(width 0.1524)
				(type default)
			)
			(layer "B.SilkS")
		)
		(fp_line
			(start -0.7874 0.4064)
			(end 0.7874 0.4064)
			(stroke
				(width 0.1524)
				(type default)
			)
			(layer "B.SilkS")
		)
		(fp_line
			(start 0.7874 -0.4064)
			(end -0.7874 -0.4064)
			(stroke
				(width 0.1524)
				(type default)
			)
			(layer "B.SilkS")
		)
		(fp_line
			(start 0.7874 0.4064)
			(end 0.7874 -0.4064)
			(stroke
				(width 0.1524)
				(type default)
			)
			(layer "B.SilkS")
		)
		(fp_line
			(start -0.67945 -0.3048)
			(end -0.67945 0.3048)
			(stroke
				(width 0.1)
				(type default)
			)
			(layer "B.Fab")
		)
		(fp_line
			(start -0.67945 0.3048)
			(end -0.120396 0.3048)
			(stroke
				(width 0.1)
				(type default)
			)
			(layer "B.Fab")
		)
		(fp_line
			(start -0.12065 -0.3048)
			(end -0.67945 -0.3048)
			(stroke
				(width 0.1)
				(type default)
			)
			(layer "B.Fab")
		)
		(fp_line
			(start -0.12065 -0.2794)
			(end -0.12065 -0.3048)
			(stroke
				(width 0.1)
				(type default)
			)
			(layer "B.Fab")
		)
		(fp_line
			(start -0.120396 0.2794)
			(end 0.12065 0.2794)
			(stroke
				(width 0.1)
				(type default)
			)
			(layer "B.Fab")
		)
		(fp_line
			(start -0.120396 0.3048)
			(end -0.120396 0.2794)
			(stroke
				(width 0.1)
				(type default)
			)
			(layer "B.Fab")
		)
		(fp_line
			(start 0.12065 -0.305054)
			(end 0.12065 -0.2794)
			(stroke
				(width 0.1)
				(type default)
			)
			(layer "B.Fab")
		)
		(fp_line
			(start 0.12065 -0.2794)
			(end -0.12065 -0.2794)
			(stroke
				(width 0.1)
				(type default)
			)
			(layer "B.Fab")
		)
		(fp_line
			(start 0.12065 0.2794)
			(end 0.12065 0.3048)
			(stroke
				(width 0.1)
				(type default)
			)
			(layer "B.Fab")
		)
		(fp_line
			(start 0.12065 0.3048)
			(end 0.67945 0.3048)
			(stroke
				(width 0.1)
				(type default)
			)
			(layer "B.Fab")
		)
		(fp_line
			(start 0.67945 -0.305054)
			(end 0.12065 -0.305054)
			(stroke
				(width 0.1)
				(type default)
			)
			(layer "B.Fab")
		)
		(fp_line
			(start 0.67945 0.3048)
			(end 0.67945 -0.305054)
			(stroke
				(width 0.1)
				(type default)
			)
			(layer "B.Fab")
		)
		(pad "1" smd circle
			(at 0.40005 0 180)
			(size 0 0)
			(layers "B.Cu" "B.Mask" "B.Paste")
			(net "PD_PCH_GPPC_A_15")
		)
		(pad "2" smd circle
			(at -0.40005 0 180)
			(size 0 0)
			(layers "B.Cu" "B.Mask" "B.Paste")
			(net "GND")
		)
	)
	(footprint ""
		(layer "B.Cu")
		(at 160.89249 -258.399534 -90)
		(property "Reference" "C476"
			(at 0 0 90)
			(layer "B.SilkS")
			(hide yes)
			(effects
				(font
					(size 1.27 1.27)
				)
				(justify mirror)
			)
		)
		(property "Value" ""
			(at 0 0 90)
			(layer "B.Fab")
			(effects
				(font
					(size 1.27 1.27)
				)
				(justify mirror)
			)
		)
		(duplicate_pad_numbers_are_jumpers no)
		(fp_line
			(start -1.524 0.762)
			(end 1.524 0.762)
			(stroke
				(width 0.1524)
				(type default)
			)
			(layer "B.SilkS")
		)
		(fp_line
			(start 1.524 0.762)
			(end 1.524 -0.762)
			(stroke
				(width 0.1524)
				(type default)
			)
			(layer "B.SilkS")
		)
		(fp_line
			(start -1.524 -0.762)
			(end -1.524 0.762)
			(stroke
				(width 0.1524)
				(type default)
			)
			(layer "B.SilkS")
		)
		(fp_line
			(start 1.524 -0.762)
			(end -1.524 -0.762)
			(stroke
				(width 0.1524)
				(type default)
			)
			(layer "B.SilkS")
		)
		(fp_line
			(start -1.1049 0.724916)
			(end -1.1049 -0.724916)
			(stroke
				(width 0.1)
				(type default)
			)
			(layer "B.Fab")
		)
		(fp_line
			(start 1.1049 0.724916)
			(end -1.1049 0.724916)
			(stroke
				(width 0.1)
				(type default)
			)
			(layer "B.Fab")
		)
		(fp_line
			(start -1.1049 -0.724916)
			(end 1.1049 -0.724916)
			(stroke
				(width 0.1)
				(type default)
			)
			(layer "B.Fab")
		)
		(fp_line
			(start 1.1049 -0.724916)
			(end 1.1049 0.724916)
			(stroke
				(width 0.1)
				(type default)
			)
			(layer "B.Fab")
		)
		(pad "1" smd rect
			(at 0.889 0 270)
			(size 1.016 1.27)
			(layers "B.Cu" "B.Mask" "B.Paste")
			(net "PVCCFA_EHV_FIVRA_CPU1")
		)
		(pad "2" smd rect
			(at -0.889 0 270)
			(size 1.016 1.27)
			(layers "B.Cu" "B.Mask" "B.Paste")
			(net "GND")
		)
	)
)
